(kicad_pcb
	(version 20260206)
	(generator "pcbnew")
	(generator_version "10.0")
	(general
		(thickness 1.6)
		(legacy_teardrops no)
	)
	(paper "A4")
	(title_block
		(title "fcb — 12433-1M.1206WZS1330.brd")
		(comment 1 "Open Vault / Knox (Wiwynn) / footprints 429-436 of 495")
	)
	(layers
		(0 "F.Cu" signal "TOP")
		(4 "In1.Cu" signal "L2GND")
		(6 "In2.Cu" signal "L3VCC")
		(2 "B.Cu" signal "BOTTOM")
		(9 "F.Adhes" user "F.Adhesive")
		(11 "B.Adhes" user "B.Adhesive")
		(13 "F.Paste" user "Package Geometry/Pastemask Top")
		(15 "B.Paste" user "Package Geometry/Pastemask Bottom")
		(5 "F.SilkS" user "Ref Des/Silkscreen Top")
		(7 "B.SilkS" user "Ref Des/Silkscreen Bottom")
		(1 "F.Mask" user "Board Geometry/Soldermask Top")
		(3 "B.Mask" user "Board Geometry/Soldermask Bottom")
		(17 "Dwgs.User" user "User.Drawings")
		(19 "Cmts.User" user "User.Comments")
		(21 "Eco1.User" user "User.Eco1")
		(23 "Eco2.User" user "User.Eco2")
		(25 "Edge.Cuts" user "Board Geometry/Outline")
		(27 "Margin" user)
		(31 "F.CrtYd" user "Package Geometry/Place Bound Top")
		(29 "B.CrtYd" user "Package Geometry/Place Bound Bottom")
		(35 "F.Fab" user "Ref Des/Assembly Top")
		(33 "B.Fab" user "Ref Des/Assembly Bottom")
	)
	(footprint ""
		(layer "F.Cu")
		(at 31.242 -361.315 180)
		(property "Reference" "R109"
			(at 0 0 180)
			(layer "F.SilkS")
			(hide yes)
			(effects
				(font
					(size 1.27 1.27)
				)
			)
		)
		(property "Value" "0R2J-2-GP"
			(at 0.064008 -3.993896 180)
			(unlocked yes)
			(layer "F.Fab")
			(hide yes)
			(effects
				(font
					(size 1.016 1.016)
					(thickness 0.1524)
				)
			)
		)
		(property "Device Type" "R402H16"
			(at 0.064008 -5.517896 180)
			(unlocked yes)
			(layer "F.Fab")
			(hide yes)
			(effects
				(font
					(size 1.016 1.016)
					(thickness 0.1524)
				)
			)
		)
		(duplicate_pad_numbers_are_jumpers no)
		(fp_line
			(start 0.508 -0.9398)
			(end -0.508 -0.9398)
			(stroke
				(width 0.1524)
				(type default)
			)
			(layer "F.SilkS")
		)
		(fp_line
			(start -0.508 -0.9398)
			(end -0.508 0.9398)
			(stroke
				(width 0.1524)
				(type default)
			)
			(layer "F.SilkS")
		)
		(fp_rect
			(start -0.508 0.9398)
			(end 0.508 -0.9398)
			(stroke
				(width 0)
				(type default)
			)
			(fill no)
			(layer "F.CrtYd")
		)
		(fp_rect
			(start -0.508 0.9398)
			(end 0.508 -0.9398)
			(stroke
				(width 0)
				(type default)
			)
			(fill no)
			(layer "F.Fab")
		)
		(pad "1" smd custom
			(at 0 -0.4445 180)
			(size 0.1397 0.1397)
			(layers "F.Cu" "F.Mask" "F.Paste")
			(net "I2C_C_SDA")
			(options
				(clearance outline)
				(anchor circle)
			)
			(primitives
				(gr_poly
					(pts
						(arc
							(start -0.1778 -0.2794)
							(mid -0.249642 -0.249642)
							(end -0.2794 -0.1778)
						)
						(arc
							(start -0.2794 0.1778)
							(mid -0.249642 0.249642)
							(end -0.1778 0.2794)
						)
						(arc
							(start 0.1778 0.2794)
							(mid 0.249642 0.249642)
							(end 0.2794 0.1778)
						)
						(arc
							(start 0.2794 -0.1778)
							(mid 0.249642 -0.249642)
							(end 0.1778 -0.2794)
						)
					)
					(width 0)
					(fill yes)
				)
			)
		)
		(pad "2" smd custom
			(at 0 0.4445 180)
			(size 0.1397 0.1397)
			(layers "F.Cu" "F.Mask" "F.Paste")
			(net "I2C_C_SDA_ADM1276")
			(options
				(clearance outline)
				(anchor circle)
			)
			(primitives
				(gr_poly
					(pts
						(arc
							(start -0.1778 -0.2794)
							(mid -0.249642 -0.249642)
							(end -0.2794 -0.1778)
						)
						(arc
							(start -0.2794 0.1778)
							(mid -0.249642 0.249642)
							(end -0.1778 0.2794)
						)
						(arc
							(start 0.1778 0.2794)
							(mid 0.249642 0.249642)
							(end 0.2794 0.1778)
						)
						(arc
							(start 0.2794 -0.1778)
							(mid 0.249642 -0.249642)
							(end 0.1778 -0.2794)
						)
					)
					(width 0)
					(fill yes)
				)
			)
		)
	)
	(footprint ""
		(layer "F.Cu")
		(at 42.0116 -362.839 180)
		(property "Reference" "PR49"
			(at 0 0 180)
			(layer "F.SilkS")
			(hide yes)
			(effects
				(font
					(size 1.27 1.27)
				)
			)
		)
		(property "Value" "4K7R2J-2-GP"
			(at 0.064008 -3.993896 180)
			(unlocked yes)
			(layer "F.Fab")
			(hide yes)
			(effects
				(font
					(size 1.016 1.016)
					(thickness 0.1524)
				)
			)
		)
		(property "Device Type" "R402H16"
			(at 0.064008 -5.517896 180)
			(unlocked yes)
			(layer "F.Fab")
			(hide yes)
			(effects
				(font
					(size 1.016 1.016)
					(thickness 0.1524)
				)
			)
		)
		(duplicate_pad_numbers_are_jumpers no)
		(fp_line
			(start 0.508 -0.9398)
			(end -0.508 -0.9398)
			(stroke
				(width 0.1524)
				(type default)
			)
			(layer "F.SilkS")
		)
		(fp_line
			(start -0.508 -0.9398)
			(end -0.508 0.9398)
			(stroke
				(width 0.1524)
				(type default)
			)
			(layer "F.SilkS")
		)
		(fp_rect
			(start -0.508 0.9398)
			(end 0.508 -0.9398)
			(stroke
				(width 0)
				(type default)
			)
			(fill no)
			(layer "F.CrtYd")
		)
		(fp_rect
			(start -0.508 0.9398)
			(end 0.508 -0.9398)
			(stroke
				(width 0)
				(type default)
			)
			(fill no)
			(layer "F.Fab")
		)
		(pad "1" smd custom
			(at 0 -0.4445 180)
			(size 0.1397 0.1397)
			(layers "F.Cu" "F.Mask" "F.Paste")
			(net "GND")
			(options
				(clearance outline)
				(anchor circle)
			)
			(primitives
				(gr_poly
					(pts
						(arc
							(start -0.1778 -0.2794)
							(mid -0.249642 -0.249642)
							(end -0.2794 -0.1778)
						)
						(arc
							(start -0.2794 0.1778)
							(mid -0.249642 0.249642)
							(end -0.1778 0.2794)
						)
						(arc
							(start 0.1778 0.2794)
							(mid 0.249642 0.249642)
							(end 0.2794 0.1778)
						)
						(arc
							(start 0.2794 -0.1778)
							(mid 0.249642 -0.249642)
							(end 0.1778 -0.2794)
						)
					)
					(width 0)
					(fill yes)
				)
			)
		)
		(pad "2" smd custom
			(at 0 0.4445 180)
			(size 0.1397 0.1397)
			(layers "F.Cu" "F.Mask" "F.Paste")
			(net "ADM1276_LATCH#")
			(options
				(clearance outline)
				(anchor circle)
			)
			(primitives
				(gr_poly
					(pts
						(arc
							(start -0.1778 -0.2794)
							(mid -0.249642 -0.249642)
							(end -0.2794 -0.1778)
						)
						(arc
							(start -0.2794 0.1778)
							(mid -0.249642 0.249642)
							(end -0.1778 0.2794)
						)
						(arc
							(start 0.1778 0.2794)
							(mid 0.249642 0.249642)
							(end 0.2794 0.1778)
						)
						(arc
							(start 0.2794 -0.1778)
							(mid 0.249642 -0.249642)
							(end 0.1778 -0.2794)
						)
					)
					(width 0)
					(fill yes)
				)
			)
		)
	)
	(footprint ""
		(layer "F.Cu")
		(at 26.4922 -250.444 -90)
		(property "Reference" "C14"
			(at 0 0 270)
			(layer "F.SilkS")
			(hide yes)
			(effects
				(font
					(size 1.27 1.27)
				)
			)
		)
		(property "Value" "SCD1U50V3KX-GP"
			(at 0 -2.8194 270)
			(unlocked yes)
			(layer "F.Fab")
			(hide yes)
			(effects
				(font
					(size 1.016 1.016)
					(thickness 0.1524)
				)
			)
		)
		(property "Device Type" "C603H36"
			(at 0 -4.3434 270)
			(unlocked yes)
			(layer "F.Fab")
			(hide yes)
			(effects
				(font
					(size 1.016 1.016)
					(thickness 0.1524)
				)
			)
		)
		(duplicate_pad_numbers_are_jumpers no)
		(fp_line
			(start 0.508 0)
			(end -0.508 0)
			(stroke
				(width 0.2032)
				(type default)
			)
			(layer "F.SilkS")
		)
		(fp_rect
			(start -0.5842 1.3335)
			(end 0.5842 -1.3335)
			(stroke
				(width 0)
				(type default)
			)
			(fill no)
			(layer "F.CrtYd")
		)
		(fp_rect
			(start -0.5842 1.3335)
			(end 0.5842 -1.3335)
			(stroke
				(width 0)
				(type default)
			)
			(fill no)
			(layer "F.Fab")
		)
		(pad "1" smd custom
			(at 0 -0.762 270)
			(size 0.2159 0.2159)
			(layers "F.Cu" "F.Mask" "F.Paste")
			(net "P3V3")
			(options
				(clearance outline)
				(anchor circle)
			)
			(primitives
				(gr_poly
					(pts
						(arc
							(start -0.3302 -0.4318)
							(mid -0.402042 -0.402042)
							(end -0.4318 -0.3302)
						)
						(arc
							(start -0.4318 0.3302)
							(mid -0.402042 0.402042)
							(end -0.3302 0.4318)
						)
						(arc
							(start 0.3302 0.4318)
							(mid 0.402042 0.402042)
							(end 0.4318 0.3302)
						)
						(arc
							(start 0.4318 -0.3302)
							(mid 0.402042 -0.402042)
							(end 0.3302 -0.4318)
						)
					)
					(width 0)
					(fill yes)
				)
			)
		)
		(pad "2" smd custom
			(at 0 0.762 270)
			(size 0.2159 0.2159)
			(layers "F.Cu" "F.Mask" "F.Paste")
			(net "GND")
			(options
				(clearance outline)
				(anchor circle)
			)
			(primitives
				(gr_poly
					(pts
						(arc
							(start -0.3302 -0.4318)
							(mid -0.402042 -0.402042)
							(end -0.4318 -0.3302)
						)
						(arc
							(start -0.4318 0.3302)
							(mid -0.402042 0.402042)
							(end -0.3302 0.4318)
						)
						(arc
							(start 0.3302 0.4318)
							(mid 0.402042 0.402042)
							(end 0.4318 0.3302)
						)
						(arc
							(start 0.4318 -0.3302)
							(mid 0.402042 -0.402042)
							(end 0.3302 -0.4318)
						)
					)
					(width 0)
					(fill yes)
				)
			)
		)
	)
	(footprint ""
		(layer "F.Cu")
		(at 29.718 -381 180)
		(property "Reference" "PR19"
			(at 0 0 180)
			(layer "F.SilkS")
			(hide yes)
			(effects
				(font
					(size 1.27 1.27)
				)
			)
		)
		(property "Value" "10R2F-L-GP"
			(at 0.064008 -3.993896 180)
			(unlocked yes)
			(layer "F.Fab")
			(hide yes)
			(effects
				(font
					(size 1.016 1.016)
					(thickness 0.1524)
				)
			)
		)
		(property "Device Type" "R402H14"
			(at 0.064008 -5.517896 180)
			(unlocked yes)
			(layer "F.Fab")
			(hide yes)
			(effects
				(font
					(size 1.016 1.016)
					(thickness 0.1524)
				)
			)
		)
		(duplicate_pad_numbers_are_jumpers no)
		(fp_line
			(start 0.508 -0.9398)
			(end -0.508 -0.9398)
			(stroke
				(width 0.1524)
				(type default)
			)
			(layer "F.SilkS")
		)
		(fp_line
			(start -0.508 -0.9398)
			(end -0.508 0.9398)
			(stroke
				(width 0.1524)
				(type default)
			)
			(layer "F.SilkS")
		)
		(fp_rect
			(start -0.508 0.9398)
			(end 0.508 -0.9398)
			(stroke
				(width 0)
				(type default)
			)
			(fill no)
			(layer "F.CrtYd")
		)
		(fp_rect
			(start -0.508 0.9398)
			(end 0.508 -0.9398)
			(stroke
				(width 0)
				(type default)
			)
			(fill no)
			(layer "F.Fab")
		)
		(pad "1" smd custom
			(at 0 -0.4445 180)
			(size 0.1397 0.1397)
			(layers "F.Cu" "F.Mask" "F.Paste")
			(net "ADM1276_SENSE+")
			(options
				(clearance outline)
				(anchor circle)
			)
			(primitives
				(gr_poly
					(pts
						(arc
							(start -0.1778 -0.2794)
							(mid -0.249642 -0.249642)
							(end -0.2794 -0.1778)
						)
						(arc
							(start -0.2794 0.1778)
							(mid -0.249642 0.249642)
							(end -0.1778 0.2794)
						)
						(arc
							(start 0.1778 0.2794)
							(mid 0.249642 0.249642)
							(end 0.2794 0.1778)
						)
						(arc
							(start 0.2794 -0.1778)
							(mid 0.249642 -0.249642)
							(end 0.1778 -0.2794)
						)
					)
					(width 0)
					(fill yes)
				)
			)
		)
		(pad "2" smd custom
			(at 0 0.4445 180)
			(size 0.1397 0.1397)
			(layers "F.Cu" "F.Mask" "F.Paste")
			(net "SENSE+_R2")
			(options
				(clearance outline)
				(anchor circle)
			)
			(primitives
				(gr_poly
					(pts
						(arc
							(start -0.1778 -0.2794)
							(mid -0.249642 -0.249642)
							(end -0.2794 -0.1778)
						)
						(arc
							(start -0.2794 0.1778)
							(mid -0.249642 0.249642)
							(end -0.1778 0.2794)
						)
						(arc
							(start 0.1778 0.2794)
							(mid 0.249642 0.249642)
							(end 0.2794 0.1778)
						)
						(arc
							(start 0.2794 -0.1778)
							(mid 0.249642 -0.249642)
							(end 0.1778 -0.2794)
						)
					)
					(width 0)
					(fill yes)
				)
			)
		)
	)
	(footprint ""
		(layer "F.Cu")
		(at 39.064184 -360.4768 90)
		(property "Reference" "PR59"
			(at 0 0 90)
			(layer "F.SilkS")
			(hide yes)
			(effects
				(font
					(size 1.27 1.27)
				)
			)
		)
		(property "Value" "4K7R2F-GP"
			(at 0.064008 -3.993896 90)
			(unlocked yes)
			(layer "F.Fab")
			(hide yes)
			(effects
				(font
					(size 1.016 1.016)
					(thickness 0.1524)
				)
			)
		)
		(property "Device Type" "R402H16"
			(at 0.064008 -5.517896 90)
			(unlocked yes)
			(layer "F.Fab")
			(hide yes)
			(effects
				(font
					(size 1.016 1.016)
					(thickness 0.1524)
				)
			)
		)
		(duplicate_pad_numbers_are_jumpers no)
		(fp_line
			(start 0.508 -0.9398)
			(end -0.508 -0.9398)
			(stroke
				(width 0.1524)
				(type default)
			)
			(layer "F.SilkS")
		)
		(fp_line
			(start -0.508 -0.9398)
			(end -0.508 0.9398)
			(stroke
				(width 0.1524)
				(type default)
			)
			(layer "F.SilkS")
		)
		(fp_rect
			(start -0.508 0.9398)
			(end 0.508 -0.9398)
			(stroke
				(width 0)
				(type default)
			)
			(fill no)
			(layer "F.CrtYd")
		)
		(fp_rect
			(start -0.508 0.9398)
			(end 0.508 -0.9398)
			(stroke
				(width 0)
				(type default)
			)
			(fill no)
			(layer "F.Fab")
		)
		(pad "1" smd custom
			(at 0 -0.4445 90)
			(size 0.1397 0.1397)
			(layers "F.Cu" "F.Mask" "F.Paste")
			(net "P12V_AUX")
			(options
				(clearance outline)
				(anchor circle)
			)
			(primitives
				(gr_poly
					(pts
						(arc
							(start -0.1778 -0.2794)
							(mid -0.249642 -0.249642)
							(end -0.2794 -0.1778)
						)
						(arc
							(start -0.2794 0.1778)
							(mid -0.249642 0.249642)
							(end -0.1778 0.2794)
						)
						(arc
							(start 0.1778 0.2794)
							(mid 0.249642 0.249642)
							(end 0.2794 0.1778)
						)
						(arc
							(start 0.2794 -0.1778)
							(mid 0.249642 -0.249642)
							(end 0.1778 -0.2794)
						)
					)
					(width 0)
					(fill yes)
				)
			)
		)
		(pad "2" smd custom
			(at 0 0.4445 90)
			(size 0.1397 0.1397)
			(layers "F.Cu" "F.Mask" "F.Paste")
			(net "OTP_RETRY_B")
			(options
				(clearance outline)
				(anchor circle)
			)
			(primitives
				(gr_poly
					(pts
						(arc
							(start -0.1778 -0.2794)
							(mid -0.249642 -0.249642)
							(end -0.2794 -0.1778)
						)
						(arc
							(start -0.2794 0.1778)
							(mid -0.249642 0.249642)
							(end -0.1778 0.2794)
						)
						(arc
							(start 0.1778 0.2794)
							(mid 0.249642 0.249642)
							(end 0.2794 0.1778)
						)
						(arc
							(start 0.2794 -0.1778)
							(mid 0.249642 -0.249642)
							(end 0.1778 -0.2794)
						)
					)
					(width 0)
					(fill yes)
				)
			)
		)
	)
	(footprint ""
		(layer "F.Cu")
		(at 17.907 -298.4754 -90)
		(property "Reference" "R92"
			(at 0 0 270)
			(layer "F.SilkS")
			(hide yes)
			(effects
				(font
					(size 1.27 1.27)
				)
			)
		)
		(property "Value" "4K7R2F-GP"
			(at 0.064008 -3.993896 270)
			(unlocked yes)
			(layer "F.Fab")
			(hide yes)
			(effects
				(font
					(size 1.016 1.016)
					(thickness 0.1524)
				)
			)
		)
		(property "Device Type" "R402H16"
			(at 0.064008 -5.517896 270)
			(unlocked yes)
			(layer "F.Fab")
			(hide yes)
			(effects
				(font
					(size 1.016 1.016)
					(thickness 0.1524)
				)
			)
		)
		(duplicate_pad_numbers_are_jumpers no)
		(fp_line
			(start -0.508 -0.9398)
			(end -0.508 0.9398)
			(stroke
				(width 0.1524)
				(type default)
			)
			(layer "F.SilkS")
		)
		(fp_line
			(start 0.508 -0.9398)
			(end -0.508 -0.9398)
			(stroke
				(width 0.1524)
				(type default)
			)
			(layer "F.SilkS")
		)
		(fp_rect
			(start -0.508 0.9398)
			(end 0.508 -0.9398)
			(stroke
				(width 0)
				(type default)
			)
			(fill no)
			(layer "F.CrtYd")
		)
		(fp_rect
			(start -0.508 0.9398)
			(end 0.508 -0.9398)
			(stroke
				(width 0)
				(type default)
			)
			(fill no)
			(layer "F.Fab")
		)
		(pad "1" smd custom
			(at 0 -0.4445 270)
			(size 0.1397 0.1397)
			(layers "F.Cu" "F.Mask" "F.Paste")
			(net "P12V")
			(options
				(clearance outline)
				(anchor circle)
			)
			(primitives
				(gr_poly
					(pts
						(arc
							(start -0.1778 -0.2794)
							(mid -0.249642 -0.249642)
							(end -0.2794 -0.1778)
						)
						(arc
							(start -0.2794 0.1778)
							(mid -0.249642 0.249642)
							(end -0.1778 0.2794)
						)
						(arc
							(start 0.1778 0.2794)
							(mid 0.249642 0.249642)
							(end 0.2794 0.1778)
						)
						(arc
							(start 0.2794 -0.1778)
							(mid 0.249642 -0.249642)
							(end 0.1778 -0.2794)
						)
					)
					(width 0)
					(fill yes)
				)
			)
		)
		(pad "2" smd custom
			(at 0 0.4445 270)
			(size 0.1397 0.1397)
			(layers "F.Cu" "F.Mask" "F.Paste")
			(net "PWM_OUT_FAN2_NET")
			(options
				(clearance outline)
				(anchor circle)
			)
			(primitives
				(gr_poly
					(pts
						(arc
							(start -0.1778 -0.2794)
							(mid -0.249642 -0.249642)
							(end -0.2794 -0.1778)
						)
						(arc
							(start -0.2794 0.1778)
							(mid -0.249642 0.249642)
							(end -0.1778 0.2794)
						)
						(arc
							(start 0.1778 0.2794)
							(mid 0.249642 0.249642)
							(end 0.2794 0.1778)
						)
						(arc
							(start 0.2794 -0.1778)
							(mid 0.249642 -0.249642)
							(end 0.1778 -0.2794)
						)
					)
					(width 0)
					(fill yes)
				)
			)
		)
	)
	(footprint ""
		(layer "F.Cu")
		(at 16.9672 -256.9972 90)
		(property "Reference" "D7"
			(at 0 0 90)
			(layer "F.SilkS")
			(hide yes)
			(effects
				(font
					(size 1.27 1.27)
				)
			)
		)
		(property "Value" "BAS16H-GP"
			(at 0 -5.5372 90)
			(unlocked yes)
			(layer "F.Fab")
			(hide yes)
			(effects
				(font
					(size 1.016 1.016)
					(thickness 0.1524)
				)
			)
		)
		(property "Device Type" "SOD123AKH48"
			(at 0 -7.0612 90)
			(unlocked yes)
			(layer "F.Fab")
			(hide yes)
			(effects
				(font
					(size 1.016 1.016)
					(thickness 0.1524)
				)
			)
		)
		(duplicate_pad_numbers_are_jumpers no)
		(fp_line
			(start 1.016 -2.667)
			(end -1.016 -2.667)
			(stroke
				(width 0.1524)
				(type default)
			)
			(layer "F.SilkS")
		)
		(fp_line
			(start -1.016 -2.667)
			(end -1.016 2.667)
			(stroke
				(width 0.1524)
				(type default)
			)
			(layer "F.SilkS")
		)
		(fp_line
			(start 1.016 2.667)
			(end 1.016 -2.667)
			(stroke
				(width 0.1524)
				(type default)
			)
			(layer "F.SilkS")
		)
		(fp_line
			(start -1.016 2.667)
			(end 1.016 2.667)
			(stroke
				(width 0.1524)
				(type default)
			)
			(layer "F.SilkS")
		)
		(fp_line
			(start 0.889 2.921)
			(end -0.889 2.921)
			(stroke
				(width 0.508)
				(type default)
			)
			(layer "F.SilkS")
		)
		(fp_rect
			(start -1.143 3.175)
			(end 1.143 -2.794)
			(stroke
				(width 0)
				(type default)
			)
			(fill no)
			(layer "F.CrtYd")
		)
		(fp_poly
			(pts
				(xy -1.143 -2.794) (xy 1.143 -2.794) (xy 1.143 3.175) (xy -1.143 3.175)
			)
			(stroke
				(width 0)
				(type default)
			)
			(fill no)
			(layer "F.Fab")
		)
		(pad "A" smd rect
			(at 0 -1.6891 90)
			(size 0.889 1.397)
			(layers "F.Cu" "F.Mask" "F.Paste")
			(net "FAN_TACH5")
		)
		(pad "K" smd rect
			(at 0 1.6891 90)
			(size 0.889 1.397)
			(layers "F.Cu" "F.Mask" "F.Paste")
			(net "P12V")
		)
	)
	(footprint ""
		(layer "F.Cu")
		(at 26.035 -17.399 90)
		(property "Reference" "D1"
			(at 0 0 90)
			(layer "F.SilkS")
			(hide yes)
			(effects
				(font
					(size 1.27 1.27)
				)
			)
		)
		(property "Value" "BAS16H-GP"
			(at 0 -5.5372 90)
			(unlocked yes)
			(layer "F.Fab")
			(hide yes)
			(effects
				(font
					(size 1.016 1.016)
					(thickness 0.1524)
				)
			)
		)
		(property "Device Type" "SOD123AKH48"
			(at 0 -7.0612 90)
			(unlocked yes)
			(layer "F.Fab")
			(hide yes)
			(effects
				(font
					(size 1.016 1.016)
					(thickness 0.1524)
				)
			)
		)
		(duplicate_pad_numbers_are_jumpers no)
		(fp_line
			(start 1.016 -2.667)
			(end -1.016 -2.667)
			(stroke
				(width 0.1524)
				(type default)
			)
			(layer "F.SilkS")
		)
		(fp_line
			(start -1.016 -2.667)
			(end -1.016 2.667)
			(stroke
				(width 0.1524)
				(type default)
			)
			(layer "F.SilkS")
		)
		(fp_line
			(start 1.016 2.667)
			(end 1.016 -2.667)
			(stroke
				(width 0.1524)
				(type default)
			)
			(layer "F.SilkS")
		)
		(fp_line
			(start -1.016 2.667)
			(end 1.016 2.667)
			(stroke
				(width 0.1524)
				(type default)
			)
			(layer "F.SilkS")
		)
		(fp_line
			(start 0.889 2.921)
			(end -0.889 2.921)
			(stroke
				(width 0.508)
				(type default)
			)
			(layer "F.SilkS")
		)
		(fp_rect
			(start -1.143 3.175)
			(end 1.143 -2.794)
			(stroke
				(width 0)
				(type default)
			)
			(fill no)
			(layer "F.CrtYd")
		)
		(fp_poly
			(pts
				(xy -1.143 -2.794) (xy 1.143 -2.794) (xy 1.143 3.175) (xy -1.143 3.175)
			)
			(stroke
				(width 0)
				(type default)
			)
			(fill no)
			(layer "F.Fab")
		)
		(pad "A" smd rect
			(at 0 -1.6891 90)
			(size 0.889 1.397)
			(layers "F.Cu" "F.Mask" "F.Paste")
			(net "FAN_TACH12")
		)
		(pad "K" smd rect
			(at 0 1.6891 90)
			(size 0.889 1.397)
			(layers "F.Cu" "F.Mask" "F.Paste")
			(net "P12V")
		)
	)
)
